# T6G (Grand Teton) — schematic netlist excerpt (pin names and nets, part order shuffled) for the footprints in the layout excerpt that follows; sources: Cadence DE-HDL packaged netlist, KiCad conversion of 04192023_DAF0TMB3IC0_F0TG_MB_C_brd_V02_OCP.brd

C339  Q_CAP  10UF 6.3V 20% X6S  pkg C0402  page 334 : A = P0V9_CPU1_RT1_2A ; B = GND
C506  Q_CAP  10UF 6.3V 20% X6S  pkg C0402  page 279 : A = P1V8_CPU0_RT_1D ; B = GND

(kicad_pcb
	(version 20260206)
	(generator "pcbnew")
	(generator_version "10.0")
	(general
		(thickness 1.6)
		(legacy_teardrops no)
	)
	(paper "A4")
	(title_block
		(title "04192023_DAF0TMB3IC0_F0TG_MB_C_brd_V02_OCP.brd")
		(comment 1 "Grand Teton / footprints 5159-5160 of 8354")
	)
	(layers
		(0 "F.Cu" signal "TOP")
		(4 "In1.Cu" signal "GND")
		(6 "In2.Cu" signal "IN1")
		(8 "In3.Cu" signal "GND1")
		(10 "In4.Cu" signal "IN2")
		(12 "In5.Cu" signal "GND2")
		(14 "In6.Cu" signal "IN3")
		(16 "In7.Cu" signal "GND3")
		(18 "In8.Cu" signal "VCC")
		(20 "In9.Cu" signal "VCC1")
		(22 "In10.Cu" signal "GND4")
		(24 "In11.Cu" signal "IN4")
		(26 "In12.Cu" signal "GND5")
		(28 "In13.Cu" signal "IN5")
		(30 "In14.Cu" signal "GND6")
		(32 "In15.Cu" signal "IN6")
		(34 "In16.Cu" signal "GND7")
		(2 "B.Cu" signal "BOTTOM")
		(9 "F.Adhes" user "F.Adhesive")
		(11 "B.Adhes" user "B.Adhesive")
		(13 "F.Paste" user "Package Geometry/Pastemask Top")
		(15 "B.Paste" user "Package Geometry/Pastemask Bottom")
		(5 "F.SilkS" user "Ref Des/Silkscreen Top")
		(7 "B.SilkS" user "Ref Des/Silkscreen Bottom")
		(1 "F.Mask" user "Board Geometry/Soldermask Top")
		(3 "B.Mask" user "Board Geometry/Soldermask Bottom")
		(17 "Dwgs.User" user "User.Drawings")
		(19 "Cmts.User" user "User.Comments")
		(21 "Eco1.User" user "User.Eco1")
		(23 "Eco2.User" user "User.Eco2")
		(25 "Edge.Cuts" user "Board Geometry/Outline")
		(27 "Margin" user)
		(31 "F.CrtYd" user "Package Geometry/Place Bound Top")
		(29 "B.CrtYd" user "Package Geometry/Place Bound Bottom")
		(35 "F.Fab" user "Ref Des/Assembly Top")
		(33 "B.Fab" user "Ref Des/Assembly Bottom")
	)
	(footprint ""
		(layer "B.Cu")
		(at 94.31909 -390.560052 90)
		(property "Reference" "C339"
			(at 0 0 90)
			(layer "B.SilkS")
			(hide yes)
			(effects
				(font
					(size 1.27 1.27)
				)
				(justify mirror)
			)
		)
		(property "Value" ""
			(at 0 0 90)
			(layer "B.Fab")
			(effects
				(font
					(size 1.27 1.27)
				)
				(justify mirror)
			)
		)
		(duplicate_pad_numbers_are_jumpers no)
		(fp_line
			(start 0.7874 -0.4064)
			(end -0.7874 -0.4064)
			(stroke
				(width 0.1524)
				(type default)
			)
			(layer "B.SilkS")
		)
		(fp_line
			(start -0.7874 -0.4064)
			(end -0.7874 0.4064)
			(stroke
				(width 0.1524)
				(type default)
			)
			(layer "B.SilkS")
		)
		(fp_line
			(start 0.7874 0.4064)
			(end 0.7874 -0.4064)
			(stroke
				(width 0.1524)
				(type default)
			)
			(layer "B.SilkS")
		)
		(fp_line
			(start -0.7874 0.4064)
			(end 0.7874 0.4064)
			(stroke
				(width 0.1524)
				(type default)
			)
			(layer "B.SilkS")
		)
		(fp_line
			(start 0.67945 -0.305054)
			(end 0.12065 -0.305054)
			(stroke
				(width 0.1)
				(type default)
			)
			(layer "B.Fab")
		)
		(fp_line
			(start 0.12065 -0.305054)
			(end 0.12065 -0.2794)
			(stroke
				(width 0.1)
				(type default)
			)
			(layer "B.Fab")
		)
		(fp_line
			(start -0.12065 -0.3048)
			(end -0.67945 -0.3048)
			(stroke
				(width 0.1)
				(type default)
			)
			(layer "B.Fab")
		)
		(fp_line
			(start -0.67945 -0.3048)
			(end -0.67945 0.3048)
			(stroke
				(width 0.1)
				(type default)
			)
			(layer "B.Fab")
		)
		(fp_line
			(start 0.12065 -0.2794)
			(end -0.12065 -0.2794)
			(stroke
				(width 0.1)
				(type default)
			)
			(layer "B.Fab")
		)
		(fp_line
			(start -0.12065 -0.2794)
			(end -0.12065 -0.3048)
			(stroke
				(width 0.1)
				(type default)
			)
			(layer "B.Fab")
		)
		(fp_line
			(start 0.12065 0.2794)
			(end 0.12065 0.3048)
			(stroke
				(width 0.1)
				(type default)
			)
			(layer "B.Fab")
		)
		(fp_line
			(start -0.120396 0.2794)
			(end 0.12065 0.2794)
			(stroke
				(width 0.1)
				(type default)
			)
			(layer "B.Fab")
		)
		(fp_line
			(start 0.67945 0.3048)
			(end 0.67945 -0.305054)
			(stroke
				(width 0.1)
				(type default)
			)
			(layer "B.Fab")
		)
		(fp_line
			(start 0.12065 0.3048)
			(end 0.67945 0.3048)
			(stroke
				(width 0.1)
				(type default)
			)
			(layer "B.Fab")
		)
		(fp_line
			(start -0.120396 0.3048)
			(end -0.120396 0.2794)
			(stroke
				(width 0.1)
				(type default)
			)
			(layer "B.Fab")
		)
		(fp_line
			(start -0.67945 0.3048)
			(end -0.120396 0.3048)
			(stroke
				(width 0.1)
				(type default)
			)
			(layer "B.Fab")
		)
		(pad "1" smd circle
			(at 0.40005 0 270)
			(size 0 0)
			(layers "B.Cu" "B.Mask" "B.Paste")
			(net "P0V9_CPU1_RT1_2A")
		)
		(pad "2" smd circle
			(at -0.40005 0 270)
			(size 0 0)
			(layers "B.Cu" "B.Mask" "B.Paste")
			(net "GND")
		)
	)
	(footprint ""
		(layer "B.Cu")
		(at 329.068176 -395.127988 -90)
		(property "Reference" "C506"
			(at 0 0 90)
			(layer "B.SilkS")
			(hide yes)
			(effects
				(font
					(size 1.27 1.27)
				)
				(justify mirror)
			)
		)
		(property "Value" ""
			(at 0 0 90)
			(layer "B.Fab")
			(effects
				(font
					(size 1.27 1.27)
				)
				(justify mirror)
			)
		)
		(duplicate_pad_numbers_are_jumpers no)
		(fp_line
			(start -0.7874 0.4064)
			(end 0.7874 0.4064)
			(stroke
				(width 0.1524)
				(type default)
			)
			(layer "B.SilkS")
		)
		(fp_line
			(start 0.7874 0.4064)
			(end 0.7874 -0.4064)
			(stroke
				(width 0.1524)
				(type default)
			)
			(layer "B.SilkS")
		)
		(fp_line
			(start -0.7874 -0.4064)
			(end -0.7874 0.4064)
			(stroke
				(width 0.1524)
				(type default)
			)
			(layer "B.SilkS")
		)
		(fp_line
			(start 0.7874 -0.4064)
			(end -0.7874 -0.4064)
			(stroke
				(width 0.1524)
				(type default)
			)
			(layer "B.SilkS")
		)
		(fp_line
			(start -0.67945 0.3048)
			(end -0.120396 0.3048)
			(stroke
				(width 0.1)
				(type default)
			)
			(layer "B.Fab")
		)
		(fp_line
			(start -0.120396 0.3048)
			(end -0.120396 0.2794)
			(stroke
				(width 0.1)
				(type default)
			)
			(layer "B.Fab")
		)
		(fp_line
			(start 0.12065 0.3048)
			(end 0.67945 0.3048)
			(stroke
				(width 0.1)
				(type default)
			)
			(layer "B.Fab")
		)
		(fp_line
			(start 0.67945 0.3048)
			(end 0.67945 -0.305054)
			(stroke
				(width 0.1)
				(type default)
			)
			(layer "B.Fab")
		)
		(fp_line
			(start -0.120396 0.2794)
			(end 0.12065 0.2794)
			(stroke
				(width 0.1)
				(type default)
			)
			(layer "B.Fab")
		)
		(fp_line
			(start 0.12065 0.2794)
			(end 0.12065 0.3048)
			(stroke
				(width 0.1)
				(type default)
			)
			(layer "B.Fab")
		)
		(fp_line
			(start -0.12065 -0.2794)
			(end -0.12065 -0.3048)
			(stroke
				(width 0.1)
				(type default)
			)
			(layer "B.Fab")
		)
		(fp_line
			(start 0.12065 -0.2794)
			(end -0.12065 -0.2794)
			(stroke
				(width 0.1)
				(type default)
			)
			(layer "B.Fab")
		)
		(fp_line
			(start -0.67945 -0.3048)
			(end -0.67945 0.3048)
			(stroke
				(width 0.1)
				(type default)
			)
			(layer "B.Fab")
		)
		(fp_line
			(start -0.12065 -0.3048)
			(end -0.67945 -0.3048)
			(stroke
				(width 0.1)
				(type default)
			)
			(layer "B.Fab")
		)
		(fp_line
			(start 0.12065 -0.305054)
			(end 0.12065 -0.2794)
			(stroke
				(width 0.1)
				(type default)
			)
			(layer "B.Fab")
		)
		(fp_line
			(start 0.67945 -0.305054)
			(end 0.12065 -0.305054)
			(stroke
				(width 0.1)
				(type default)
			)
			(layer "B.Fab")
		)
		(pad "1" smd circle
			(at 0.40005 0 90)
			(size 0 0)
			(layers "B.Cu" "B.Mask" "B.Paste")
			(net "P1V8_CPU0_RT_1D")
		)
		(pad "2" smd circle
			(at -0.40005 0 90)
			(size 0 0)
			(layers "B.Cu" "B.Mask" "B.Paste")
			(net "GND")
		)
	)
)
